# T6G (Grand Teton) — schematic netlist excerpt (pin names and nets, part order shuffled) for the footprints in the layout excerpt that follows; sources: Cadence DE-HDL packaged netlist, KiCad conversion of 04192023_DAF0TMB3IC0_F0TG_MB_C_brd_V02_OCP.brd

PC21  Q_CAP  0.1UF 25V 10% X7R  pkg 0402  page 226 : A = PVDD18_S5_P1 ; B = GND
R3471  Q_RES  10K 1% EMPTY  pkg 0402LF  page 126 : A = GPU_WP_HW_CTRL_N ; B = GND
R1048  Q_RES  4.7K 5% EMPTY  pkg 0201LF  page 298 : A = MODE_RT_CPU0_P2 ; B = GND

(kicad_pcb
	(version 20260206)
	(generator "pcbnew")
	(generator_version "10.0")
	(general
		(thickness 1.6)
		(legacy_teardrops no)
	)
	(paper "A4")
	(title_block
		(title "04192023_DAF0TMB3IC0_F0TG_MB_C_brd_V02_OCP.brd")
		(comment 1 "Grand Teton / footprints 2517-2520 of 8354")
	)
	(layers
		(0 "F.Cu" signal "TOP")
		(4 "In1.Cu" signal "GND")
		(6 "In2.Cu" signal "IN1")
		(8 "In3.Cu" signal "GND1")
		(10 "In4.Cu" signal "IN2")
		(12 "In5.Cu" signal "GND2")
		(14 "In6.Cu" signal "IN3")
		(16 "In7.Cu" signal "GND3")
		(18 "In8.Cu" signal "VCC")
		(20 "In9.Cu" signal "VCC1")
		(22 "In10.Cu" signal "GND4")
		(24 "In11.Cu" signal "IN4")
		(26 "In12.Cu" signal "GND5")
		(28 "In13.Cu" signal "IN5")
		(30 "In14.Cu" signal "GND6")
		(32 "In15.Cu" signal "IN6")
		(34 "In16.Cu" signal "GND7")
		(2 "B.Cu" signal "BOTTOM")
		(9 "F.Adhes" user "F.Adhesive")
		(11 "B.Adhes" user "B.Adhesive")
		(13 "F.Paste" user "Package Geometry/Pastemask Top")
		(15 "B.Paste" user "Package Geometry/Pastemask Bottom")
		(5 "F.SilkS" user "Ref Des/Silkscreen Top")
		(7 "B.SilkS" user "Ref Des/Silkscreen Bottom")
		(1 "F.Mask" user "Board Geometry/Soldermask Top")
		(3 "B.Mask" user "Board Geometry/Soldermask Bottom")
		(17 "Dwgs.User" user "User.Drawings")
		(19 "Cmts.User" user "User.Comments")
		(21 "Eco1.User" user "User.Eco1")
		(23 "Eco2.User" user "User.Eco2")
		(25 "Edge.Cuts" user "Board Geometry/Outline")
		(27 "Margin" user)
		(31 "F.CrtYd" user "Package Geometry/Place Bound Top")
		(29 "B.CrtYd" user "Package Geometry/Place Bound Bottom")
		(35 "F.Fab" user "Ref Des/Assembly Top")
		(33 "B.Fab" user "Ref Des/Assembly Bottom")
	)
	(footprint ""
		(layer "F.Cu")
		(at 438.056782 -435.27726 90)
		(property "Reference" "R3471"
			(at 0 0 90)
			(layer "F.SilkS")
			(hide yes)
			(effects
				(font
					(size 1.27 1.27)
				)
			)
		)
		(property "Value" ""
			(at 0 0 90)
			(layer "F.Fab")
			(effects
				(font
					(size 1.27 1.27)
				)
			)
		)
		(duplicate_pad_numbers_are_jumpers no)
		(fp_line
			(start 0.7874 -0.4064)
			(end 0.7874 0.4064)
			(stroke
				(width 0.1524)
				(type default)
			)
			(layer "F.SilkS")
		)
		(fp_line
			(start -0.7874 -0.4064)
			(end 0.7874 -0.4064)
			(stroke
				(width 0.1524)
				(type default)
			)
			(layer "F.SilkS")
		)
		(fp_line
			(start 0.7874 0.4064)
			(end -0.7874 0.4064)
			(stroke
				(width 0.1524)
				(type default)
			)
			(layer "F.SilkS")
		)
		(fp_line
			(start -0.7874 0.4064)
			(end -0.7874 -0.4064)
			(stroke
				(width 0.1524)
				(type default)
			)
			(layer "F.SilkS")
		)
		(fp_line
			(start -0.12065 -0.305054)
			(end -0.12065 -0.2794)
			(stroke
				(width 0.1)
				(type default)
			)
			(layer "F.Fab")
		)
		(fp_line
			(start -0.67945 -0.305054)
			(end -0.12065 -0.305054)
			(stroke
				(width 0.1)
				(type default)
			)
			(layer "F.Fab")
		)
		(fp_line
			(start 0.67945 -0.3048)
			(end 0.67945 0.3048)
			(stroke
				(width 0.1)
				(type default)
			)
			(layer "F.Fab")
		)
		(fp_line
			(start 0.12065 -0.3048)
			(end 0.67945 -0.3048)
			(stroke
				(width 0.1)
				(type default)
			)
			(layer "F.Fab")
		)
		(fp_line
			(start 0.12065 -0.2794)
			(end 0.12065 -0.3048)
			(stroke
				(width 0.1)
				(type default)
			)
			(layer "F.Fab")
		)
		(fp_line
			(start -0.12065 -0.2794)
			(end 0.12065 -0.2794)
			(stroke
				(width 0.1)
				(type default)
			)
			(layer "F.Fab")
		)
		(fp_line
			(start 0.120396 0.2794)
			(end -0.12065 0.2794)
			(stroke
				(width 0.1)
				(type default)
			)
			(layer "F.Fab")
		)
		(fp_line
			(start -0.12065 0.2794)
			(end -0.12065 0.3048)
			(stroke
				(width 0.1)
				(type default)
			)
			(layer "F.Fab")
		)
		(fp_line
			(start 0.67945 0.3048)
			(end 0.120396 0.3048)
			(stroke
				(width 0.1)
				(type default)
			)
			(layer "F.Fab")
		)
		(fp_line
			(start 0.120396 0.3048)
			(end 0.120396 0.2794)
			(stroke
				(width 0.1)
				(type default)
			)
			(layer "F.Fab")
		)
		(fp_line
			(start -0.12065 0.3048)
			(end -0.67945 0.3048)
			(stroke
				(width 0.1)
				(type default)
			)
			(layer "F.Fab")
		)
		(fp_line
			(start -0.67945 0.3048)
			(end -0.67945 -0.305054)
			(stroke
				(width 0.1)
				(type default)
			)
			(layer "F.Fab")
		)
		(pad "1" smd circle
			(at -0.40005 0 90)
			(size 0 0)
			(layers "F.Cu" "F.Mask" "F.Paste")
			(net "GPU_WP_HW_CTRL_N")
		)
		(pad "2" smd circle
			(at 0.40005 0 90)
			(size 0 0)
			(layers "F.Cu" "F.Mask" "F.Paste")
			(net "GND")
		)
	)
	(footprint ""
		(layer "F.Cu")
		(at 139.420092 -355.91242)
		(property "Reference" "ME6"
			(at 0.1143 -8.208518 0)
			(unlocked yes)
			(layer "F.SilkS")
			(effects
				(font
					(size 0.254 0.127)
					(thickness 0.000001)
				)
				(justify left)
			)
		)
		(property "Value" ""
			(at 0 0 0)
			(layer "F.Fab")
			(effects
				(font
					(size 1.27 1.27)
				)
			)
		)
		(duplicate_pad_numbers_are_jumpers no)
		(fp_poly
			(pts
				(xy 0 0) (xy 14.99997 0) (xy 14.99997 -7.999984) (xy 0 -7.999984)
			)
			(stroke
				(width 0)
				(type default)
			)
			(fill no)
			(layer "F.CrtYd")
		)
	)
	(footprint ""
		(layer "F.Cu")
		(at 401.128484 -402.548852 -90)
		(property "Reference" "R1048"
			(at 0 0 270)
			(layer "F.SilkS")
			(hide yes)
			(effects
				(font
					(size 1.27 1.27)
				)
			)
		)
		(property "Value" ""
			(at 0 0 270)
			(layer "F.Fab")
			(effects
				(font
					(size 1.27 1.27)
				)
			)
		)
		(duplicate_pad_numbers_are_jumpers no)
		(fp_line
			(start -0.32512 0.175006)
			(end -0.32512 -0.175006)
			(stroke
				(width 0.1)
				(type default)
			)
			(layer "F.Fab")
		)
		(fp_line
			(start 0.32512 0.175006)
			(end -0.32512 0.175006)
			(stroke
				(width 0.1)
				(type default)
			)
			(layer "F.Fab")
		)
		(fp_line
			(start -0.32512 -0.175006)
			(end 0.32512 -0.175006)
			(stroke
				(width 0.1)
				(type default)
			)
			(layer "F.Fab")
		)
		(fp_line
			(start 0.32512 -0.175006)
			(end 0.32512 0.175006)
			(stroke
				(width 0.1)
				(type default)
			)
			(layer "F.Fab")
		)
		(pad "1" smd rect
			(at -0.2667 0 270)
			(size 0.3048 0.381)
			(layers "F.Cu" "F.Mask" "F.Paste")
			(net "MODE_RT_CPU0_P2")
		)
		(pad "2" smd rect
			(at 0.2667 0 90)
			(size 0.3048 0.381)
			(layers "F.Cu" "F.Mask" "F.Paste")
			(net "GND")
		)
	)
	(footprint ""
		(layer "F.Cu")
		(at 58.580782 -145.066766)
		(property "Reference" "PC21"
			(at 0 0 0)
			(layer "F.SilkS")
			(hide yes)
			(effects
				(font
					(size 1.27 1.27)
				)
			)
		)
		(property "Value" ""
			(at 0 0 0)
			(layer "F.Fab")
			(effects
				(font
					(size 1.27 1.27)
				)
			)
		)
		(duplicate_pad_numbers_are_jumpers no)
		(fp_line
			(start -0.7874 -0.4064)
			(end 0.7874 -0.4064)
			(stroke
				(width 0.1524)
				(type default)
			)
			(layer "F.SilkS")
		)
		(fp_line
			(start -0.7874 0.4064)
			(end -0.7874 -0.4064)
			(stroke
				(width 0.1524)
				(type default)
			)
			(layer "F.SilkS")
		)
		(fp_line
			(start 0.7874 -0.4064)
			(end 0.7874 0.4064)
			(stroke
				(width 0.1524)
				(type default)
			)
			(layer "F.SilkS")
		)
		(fp_line
			(start 0.7874 0.4064)
			(end -0.7874 0.4064)
			(stroke
				(width 0.1524)
				(type default)
			)
			(layer "F.SilkS")
		)
		(fp_line
			(start -0.67945 -0.305054)
			(end -0.12065 -0.305054)
			(stroke
				(width 0.1)
				(type default)
			)
			(layer "F.Fab")
		)
		(fp_line
			(start -0.67945 0.3048)
			(end -0.67945 -0.305054)
			(stroke
				(width 0.1)
				(type default)
			)
			(layer "F.Fab")
		)
		(fp_line
			(start -0.12065 -0.305054)
			(end -0.12065 -0.2794)
			(stroke
				(width 0.1)
				(type default)
			)
			(layer "F.Fab")
		)
		(fp_line
			(start -0.12065 -0.2794)
			(end 0.12065 -0.2794)
			(stroke
				(width 0.1)
				(type default)
			)
			(layer "F.Fab")
		)
		(fp_line
			(start -0.12065 0.2794)
			(end -0.12065 0.3048)
			(stroke
				(width 0.1)
				(type default)
			)
			(layer "F.Fab")
		)
		(fp_line
			(start -0.12065 0.3048)
			(end -0.67945 0.3048)
			(stroke
				(width 0.1)
				(type default)
			)
			(layer "F.Fab")
		)
		(fp_line
			(start 0.120396 0.2794)
			(end -0.12065 0.2794)
			(stroke
				(width 0.1)
				(type default)
			)
			(layer "F.Fab")
		)
		(fp_line
			(start 0.120396 0.3048)
			(end 0.120396 0.2794)
			(stroke
				(width 0.1)
				(type default)
			)
			(layer "F.Fab")
		)
		(fp_line
			(start 0.12065 -0.3048)
			(end 0.67945 -0.3048)
			(stroke
				(width 0.1)
				(type default)
			)
			(layer "F.Fab")
		)
		(fp_line
			(start 0.12065 -0.2794)
			(end 0.12065 -0.3048)
			(stroke
				(width 0.1)
				(type default)
			)
			(layer "F.Fab")
		)
		(fp_line
			(start 0.67945 -0.3048)
			(end 0.67945 0.3048)
			(stroke
				(width 0.1)
				(type default)
			)
			(layer "F.Fab")
		)
		(fp_line
			(start 0.67945 0.3048)
			(end 0.120396 0.3048)
			(stroke
				(width 0.1)
				(type default)
			)
			(layer "F.Fab")
		)
		(pad "1" smd circle
			(at -0.40005 0)
			(size 0 0)
			(layers "F.Cu" "F.Mask" "F.Paste")
			(net "PVDD18_S5_P1")
		)
		(pad "2" smd circle
			(at 0.40005 0)
			(size 0 0)
			(layers "F.Cu" "F.Mask" "F.Paste")
			(net "GND")
		)
	)
)
